(kicad_pcb
	(version 20241229)
	(generator "pcbnew")
	(generator_version "9.0")
	(general
		(thickness 1.599998)
		(legacy_teardrops no)
	)
	(paper "A4")
	(title_block
		(title "Artix - Datacenter Secure Control Module (DC-SCM)")
		(date "2024-11-06")
		(rev "1.1.3")
		(comment 9 "footprint 110 of 544 (U14), pads 239-320 of 484")
	)
	(layers
		(0 "F.Cu" signal)
		(4 "In1.Cu" signal)
		(6 "In2.Cu" signal)
		(8 "In3.Cu" signal)
		(10 "In4.Cu" signal)
		(12 "In5.Cu" signal)
		(14 "In6.Cu" signal)
		(2 "B.Cu" signal)
		(9 "F.Adhes" user "F.Adhesive")
		(11 "B.Adhes" user "B.Adhesive")
		(13 "F.Paste" user)
		(15 "B.Paste" user)
		(5 "F.SilkS" user "F.Silkscreen")
		(7 "B.SilkS" user "B.Silkscreen")
		(1 "F.Mask" user)
		(3 "B.Mask" user)
		(17 "Dwgs.User" user "User.Drawings")
		(19 "Cmts.User" user "User.Comments")
		(21 "Eco1.User" user "User.Eco1")
		(23 "Eco2.User" user "User.Eco2")
		(25 "Edge.Cuts" user)
		(27 "Margin" user)
		(31 "F.CrtYd" user "F.Courtyard")
		(29 "B.CrtYd" user "B.Courtyard")
		(35 "F.Fab" user)
		(33 "B.Fab" user)
	)
	(footprint "antmicro-footprints:BGA-484_23x23mm_Layout22x22_P1mm_FGG484"
		(layer "F.Cu")
		(at 101.275 119.675 90)
		(property "Reference" "U14"
			(at 11.965 9.405 180)
			(layer "F.SilkS")
			(effects
				(font
					(size 0.7 0.7)
					(thickness 0.15)
				)
				(justify left bottom)
			)
		)
		(property "Value" "XC7A100T-FGG484"
			(at 0 13.1 90)
			(layer "F.Fab")
			(effects
				(font
					(size 0.7 0.7)
					(thickness 0.15)
				)
				(justify left bottom)
			)
		)
		(property "Datasheet" "https://docs.xilinx.com/v/u/en-US/ds181_Artix_7_Data_Sheet"
			(at 0 0 90)
			(layer "F.Fab")
			(hide yes)
			(effects
				(font
					(size 1.27 1.27)
					(thickness 0.15)
				)
			)
		)
		(property "Description" "Artix-7 Field Programmable Gate Array IC 210 324-LFBGA, CSPBGA"
			(at 0 0 90)
			(layer "F.Fab")
			(hide yes)
			(effects
				(font
					(size 1.27 1.27)
					(thickness 0.15)
				)
			)
		)
		(property "Author" "Antmicro"
			(at 220.95 18.4 0)
			(layer "F.Fab")
			(hide yes)
			(effects
				(font
					(size 1 1)
					(thickness 0.15)
				)
			)
		)
		(property "License" "Apache-2.0"
			(at 220.95 18.4 0)
			(layer "F.Fab")
			(hide yes)
			(effects
				(font
					(size 1 1)
					(thickness 0.15)
				)
			)
		)
		(property "MPN" "XC7A100T-FGG484"
			(at 220.95 18.4 0)
			(layer "F.Fab")
			(hide yes)
			(effects
				(font
					(size 1 1)
					(thickness 0.15)
				)
			)
		)
		(property "Manufacturer" "AMD-Xilinx"
			(at 220.95 18.4 0)
			(layer "F.Fab")
			(hide yes)
			(effects
				(font
					(size 1 1)
					(thickness 0.15)
				)
			)
		)
		(sheetname "/FPGA power supply/")
		(sheetfile "fpga-power-supply.kicad_sch")
		(solder_mask_margin 0.05)
		(attr smd)
		(pad "J19" smd circle
			(at 7.499 -2.5 90)
			(size 0.5 0.5)
			(layers "F.Cu" "F.Mask" "F.Paste")
			(net 421 "RGMII_TX_CLK")
			(pinfunction "IO_L12P_T1_MRCC_15")
			(pintype "bidirectional")
		)
		(pad "J20" smd circle
			(at 8.499 -2.5 90)
			(size 0.5 0.5)
			(layers "F.Cu" "F.Mask" "F.Paste")
			(net 610 "unconnected-(U14B-IO_L11P_T1_SRCC_15-PadJ20)")
			(pinfunction "IO_L11P_T1_SRCC_15")
			(pintype "bidirectional+no_connect")
		)
		(pad "J21" smd circle
			(at 9.499 -2.5 90)
			(size 0.5 0.5)
			(layers "F.Cu" "F.Mask" "F.Paste")
			(net 422 "RGMII_TXD3")
			(pinfunction "IO_L11N_T1_SRCC_15")
			(pintype "bidirectional")
		)
		(pad "J22" smd circle
			(at 10.499 -2.5 90)
			(size 0.5 0.5)
			(layers "F.Cu" "F.Mask" "F.Paste")
			(net 427 "RGMII_TX_DV")
			(pinfunction "IO_L7P_T1_AD2P_15")
			(pintype "bidirectional")
		)
		(pad "K1" smd circle
			(at -10.5 -1.5 90)
			(size 0.5 0.5)
			(layers "F.Cu" "F.Mask" "F.Paste")
			(net 189 "DDR3_DQ4")
			(pinfunction "IO_L7P_T1_AD6P_35")
			(pintype "bidirectional")
		)
		(pad "K2" smd circle
			(at -9.5 -1.5 90)
			(size 0.5 0.5)
			(layers "F.Cu" "F.Mask" "F.Paste")
			(net 477 "DDR3_DQS0_P")
			(pinfunction "IO_L9P_T1_DQS_AD7P_35")
			(pintype "bidirectional")
		)
		(pad "K3" smd circle
			(at -8.5 -1.5 90)
			(size 0.5 0.5)
			(layers "F.Cu" "F.Mask" "F.Paste")
			(net 166 "DDR3_CAS")
			(pinfunction "IO_L14N_T2_SRCC_35")
			(pintype "bidirectional")
		)
		(pad "K4" smd circle
			(at -7.5 -1.5 90)
			(size 0.5 0.5)
			(layers "F.Cu" "F.Mask" "F.Paste")
			(net 161 "DDR3_ODT")
			(pinfunction "IO_L13P_T2_MRCC_35")
			(pintype "bidirectional")
		)
		(pad "K5" smd circle
			(at -6.5 -1.5 90)
			(size 0.5 0.5)
			(layers "F.Cu" "F.Mask" "F.Paste")
			(net 1 "GND")
			(pinfunction "GND")
			(pintype "passive")
		)
		(pad "K6" smd circle
			(at -5.5 -1.5 90)
			(size 0.5 0.5)
			(layers "F.Cu" "F.Mask" "F.Paste")
			(net 155 "DDR3_BA1")
			(pinfunction "IO_L17P_T2_35")
			(pintype "bidirectional")
		)
		(pad "K7" smd circle
			(at -4.5 -1.5 90)
			(size 0.5 0.5)
			(layers "F.Cu" "F.Mask" "F.Paste")
			(net 1 "GND")
			(pinfunction "GND")
			(pintype "passive")
		)
		(pad "K8" smd circle
			(at -3.5 -1.5 90)
			(size 0.5 0.5)
			(layers "F.Cu" "F.Mask" "F.Paste")
			(net 6 "VCC1V0")
			(pinfunction "VCCINT")
			(pintype "passive")
		)
		(pad "K9" smd circle
			(at -2.5 -1.5 90)
			(size 0.5 0.5)
			(layers "F.Cu" "F.Mask" "F.Paste")
			(net 1 "GND")
			(pinfunction "GND_ADC")
			(pintype "power_in")
		)
		(pad "K10" smd circle
			(at -1.5 -1.5 90)
			(size 0.5 0.5)
			(layers "F.Cu" "F.Mask" "F.Paste")
			(net 5 "VCC1V8")
			(pinfunction "VCCADC")
			(pintype "power_in")
		)
		(pad "K11" smd circle
			(at -0.5 -1.5 90)
			(size 0.5 0.5)
			(layers "F.Cu" "F.Mask" "F.Paste")
			(net 1 "GND")
			(pinfunction "GND")
			(pintype "passive")
		)
		(pad "K12" smd circle
			(at 0.498 -1.5 90)
			(size 0.5 0.5)
			(layers "F.Cu" "F.Mask" "F.Paste")
			(net 5 "VCC1V8")
			(pinfunction "VCCAUX")
			(pintype "passive")
		)
		(pad "K13" smd circle
			(at 1.499 -1.5 90)
			(size 0.5 0.5)
			(layers "F.Cu" "F.Mask" "F.Paste")
			(net 30 "I2C[4]_SCL")
			(pinfunction "IO_L19P_T3_A22_15")
			(pintype "bidirectional")
		)
		(pad "K14" smd circle
			(at 2.499 -1.5 90)
			(size 0.5 0.5)
			(layers "F.Cu" "F.Mask" "F.Paste")
			(net 19 "I2C[3]_SCL")
			(pinfunction "IO_L19N_T3_A21_VREF_15")
			(pintype "bidirectional")
		)
		(pad "K15" smd circle
			(at 3.499 -1.5 90)
			(size 0.5 0.5)
			(layers "F.Cu" "F.Mask" "F.Paste")
			(net 1 "GND")
			(pinfunction "GND")
			(pintype "passive")
		)
		(pad "K16" smd circle
			(at 4.498 -1.5 90)
			(size 0.5 0.5)
			(layers "F.Cu" "F.Mask" "F.Paste")
			(net 67 "ESPI_IO2")
			(pinfunction "IO_L23N_T3_FWE_B_15")
			(pintype "bidirectional")
		)
		(pad "K17" smd circle
			(at 5.499 -1.5 90)
			(size 0.5 0.5)
			(layers "F.Cu" "F.Mask" "F.Paste")
			(net 65 "ESPI_IO0")
			(pinfunction "IO_L21P_T3_DQS_15")
			(pintype "bidirectional")
		)
		(pad "K18" smd circle
			(at 6.499 -1.5 90)
			(size 0.5 0.5)
			(layers "F.Cu" "F.Mask" "F.Paste")
			(net 62 "ESPI_CS0_N")
			(pinfunction "IO_L13P_T2_MRCC_15")
			(pintype "bidirectional")
		)
		(pad "K19" smd circle
			(at 7.499 -1.5 90)
			(size 0.5 0.5)
			(layers "F.Cu" "F.Mask" "F.Paste")
			(net 412 "RGMII_RX_CLK")
			(pinfunction "IO_L13N_T2_MRCC_15")
			(pintype "bidirectional")
		)
		(pad "K20" smd circle
			(at 8.499 -1.5 90)
			(size 0.5 0.5)
			(layers "F.Cu" "F.Mask" "F.Paste")
			(net 2 "VCC3V3")
			(pinfunction "VCCO_15")
			(pintype "passive")
		)
		(pad "K21" smd circle
			(at 9.499 -1.5 90)
			(size 0.5 0.5)
			(layers "F.Cu" "F.Mask" "F.Paste")
			(net 409 "RGMII_RXD2")
			(pinfunction "IO_L9P_T1_DQS_AD3P_15")
			(pintype "bidirectional")
		)
		(pad "K22" smd circle
			(at 10.499 -1.5 90)
			(size 0.5 0.5)
			(layers "F.Cu" "F.Mask" "F.Paste")
			(net 410 "RGMII_RXD3")
			(pinfunction "IO_L9N_T1_DQS_AD3N_15")
			(pintype "bidirectional")
		)
		(pad "L1" smd circle
			(at -10.5 -0.5 90)
			(size 0.5 0.5)
			(layers "F.Cu" "F.Mask" "F.Paste")
			(net 153 "DDR3_WE")
			(pinfunction "IO_L15N_T2_DQS_35")
			(pintype "bidirectional")
		)
		(pad "L2" smd circle
			(at -9.5 -0.5 90)
			(size 0.5 0.5)
			(layers "F.Cu" "F.Mask" "F.Paste")
			(net 1 "GND")
			(pinfunction "GND")
			(pintype "passive")
		)
		(pad "L3" smd circle
			(at -8.5 -0.5 90)
			(size 0.5 0.5)
			(layers "F.Cu" "F.Mask" "F.Paste")
			(net 164 "DDR3_BA0")
			(pinfunction "IO_L14P_T2_SRCC_35")
			(pintype "bidirectional")
		)
		(pad "L4" smd circle
			(at -7.5 -0.5 90)
			(size 0.5 0.5)
			(layers "F.Cu" "F.Mask" "F.Paste")
			(net 152 "DDR3_BA2")
			(pinfunction "IO_L18N_T2_35")
			(pintype "bidirectional")
		)
		(pad "L5" smd circle
			(at -6.5 -0.5 90)
			(size 0.5 0.5)
			(layers "F.Cu" "F.Mask" "F.Paste")
			(net 154 "DDR3_A10")
			(pinfunction "IO_L18P_T2_35")
			(pintype "bidirectional")
		)
		(pad "L6" smd circle
			(at -5.5 -0.5 90)
			(size 0.5 0.5)
			(layers "F.Cu" "F.Mask" "F.Paste")
			(net 159 "DDR3_A4")
			(pinfunction "IO_25_35")
			(pintype "bidirectional")
		)
		(pad "L7" smd circle
			(at -4.5 -0.5 90)
			(size 0.5 0.5)
			(layers "F.Cu" "F.Mask" "F.Paste")
			(net 6 "VCC1V0")
			(pinfunction "VCCINT")
			(pintype "passive")
		)
		(pad "L8" smd circle
			(at -3.5 -0.5 90)
			(size 0.5 0.5)
			(layers "F.Cu" "F.Mask" "F.Paste")
			(net 1 "GND")
			(pinfunction "GND")
			(pintype "passive")
		)
		(pad "L9" smd circle
			(at -2.5 -0.5 90)
			(size 0.5 0.5)
			(layers "F.Cu" "F.Mask" "F.Paste")
			(net 1 "GND")
			(pinfunction "VREFN_0")
			(pintype "bidirectional")
		)
		(pad "L10" smd circle
			(at -1.5 -0.5 90)
			(size 0.5 0.5)
			(layers "F.Cu" "F.Mask" "F.Paste")
			(net 1 "GND")
			(pinfunction "VP_0")
			(pintype "bidirectional")
		)
		(pad "L11" smd circle
			(at -0.5 -0.5 90)
			(size 0.5 0.5)
			(layers "F.Cu" "F.Mask" "F.Paste")
			(net 6 "VCC1V0")
			(pinfunction "VCCBRAM")
			(pintype "passive")
		)
		(pad "L12" smd circle
			(at 0.498 -0.5 90)
			(size 0.5 0.5)
			(layers "F.Cu" "F.Mask" "F.Paste")
			(net 320 "ROT_QSPI_SCK")
			(pinfunction "CCLK_0")
			(pintype "bidirectional")
		)
		(pad "L13" smd circle
			(at 1.499 -0.5 90)
			(size 0.5 0.5)
			(layers "F.Cu" "F.Mask" "F.Paste")
			(net 27 "I2C[4]_SDA")
			(pinfunction "IO_L20N_T3_A19_15")
			(pintype "bidirectional")
		)
		(pad "L14" smd circle
			(at 2.499 -0.5 90)
			(size 0.5 0.5)
			(layers "F.Cu" "F.Mask" "F.Paste")
			(net 26 "I2C[2]_SCL")
			(pinfunction "IO_L22P_T3_A17_15")
			(pintype "bidirectional")
		)
		(pad "L15" smd circle
			(at 3.499 -0.5 90)
			(size 0.5 0.5)
			(layers "F.Cu" "F.Mask" "F.Paste")
			(net 22 "I2C[1]_SCL")
			(pinfunction "IO_L22N_T3_A16_15")
			(pintype "bidirectional")
		)
		(pad "L16" smd circle
			(at 4.498 -0.5 90)
			(size 0.5 0.5)
			(layers "F.Cu" "F.Mask" "F.Paste")
			(net 68 "ESPI_IO3")
			(pinfunction "IO_L23P_T3_FOE_B_15")
			(pintype "bidirectional")
		)
		(pad "L17" smd circle
			(at 5.499 -0.5 90)
			(size 0.5 0.5)
			(layers "F.Cu" "F.Mask" "F.Paste")
			(net 2 "VCC3V3")
			(pinfunction "VCCO_15")
			(pintype "passive")
		)
		(pad "L18" smd circle
			(at 6.499 -0.5 90)
			(size 0.5 0.5)
			(layers "F.Cu" "F.Mask" "F.Paste")
			(net 61 "ESPI_CLK")
			(pinfunction "IO_L16N_T2_A27_15")
			(pintype "bidirectional")
		)
		(pad "L19" smd circle
			(at 7.499 -0.5 90)
			(size 0.5 0.5)
			(layers "F.Cu" "F.Mask" "F.Paste")
			(net 611 "unconnected-(U14B-IO_L14P_T2_SRCC_15-PadL19)")
			(pinfunction "IO_L14P_T2_SRCC_15")
			(pintype "bidirectional+no_connect")
		)
		(pad "L20" smd circle
			(at 8.499 -0.5 90)
			(size 0.5 0.5)
			(layers "F.Cu" "F.Mask" "F.Paste")
			(net 407 "RGMII_RXD0")
			(pinfunction "IO_L14N_T2_SRCC_15")
			(pintype "bidirectional")
		)
		(pad "L21" smd circle
			(at 9.499 -0.5 90)
			(size 0.5 0.5)
			(layers "F.Cu" "F.Mask" "F.Paste")
			(net 408 "RGMII_RXD1")
			(pinfunction "IO_L10N_T1_AD11N_15")
			(pintype "bidirectional")
		)
		(pad "L22" smd circle
			(at 10.499 -0.5 90)
			(size 0.5 0.5)
			(layers "F.Cu" "F.Mask" "F.Paste")
			(net 1 "GND")
			(pinfunction "GND")
			(pintype "passive")
		)
		(pad "M1" smd circle
			(at -10.5 0.498 90)
			(size 0.5 0.5)
			(layers "F.Cu" "F.Mask" "F.Paste")
			(net 165 "DDR3_A3")
			(pinfunction "IO_L15P_T2_DQS_35")
			(pintype "bidirectional")
		)
		(pad "M2" smd circle
			(at -9.5 0.498 90)
			(size 0.5 0.5)
			(layers "F.Cu" "F.Mask" "F.Paste")
			(net 158 "DDR3_A0")
			(pinfunction "IO_L16N_T2_35")
			(pintype "bidirectional")
		)
		(pad "M3" smd circle
			(at -8.5 0.498 90)
			(size 0.5 0.5)
			(layers "F.Cu" "F.Mask" "F.Paste")
			(net 147 "DDR3_A2")
			(pinfunction "IO_L16P_T2_35")
			(pintype "bidirectional")
		)
		(pad "M4" smd circle
			(at -7.5 0.498 90)
			(size 0.5 0.5)
			(layers "F.Cu" "F.Mask" "F.Paste")
			(net 3 "VCC1V35")
			(pinfunction "VCCO_35")
			(pintype "passive")
		)
		(pad "M5" smd circle
			(at -6.5 0.498 90)
			(size 0.5 0.5)
			(layers "F.Cu" "F.Mask" "F.Paste")
			(net 157 "DDR3_A1")
			(pinfunction "IO_L23N_T3_35")
			(pintype "bidirectional")
		)
		(pad "M6" smd circle
			(at -5.5 0.498 90)
			(size 0.5 0.5)
			(layers "F.Cu" "F.Mask" "F.Paste")
			(net 145 "DDR3_A8")
			(pinfunction "IO_L23P_T3_35")
			(pintype "bidirectional")
		)
		(pad "M7" smd circle
			(at -4.5 0.498 90)
			(size 0.5 0.5)
			(layers "F.Cu" "F.Mask" "F.Paste")
			(net 1 "GND")
			(pinfunction "GND")
			(pintype "passive")
		)
		(pad "M8" smd circle
			(at -3.5 0.498 90)
			(size 0.5 0.5)
			(layers "F.Cu" "F.Mask" "F.Paste")
			(net 6 "VCC1V0")
			(pinfunction "VCCINT")
			(pintype "passive")
		)
		(pad "M9" smd circle
			(at -2.5 0.498 90)
			(size 0.5 0.5)
			(layers "F.Cu" "F.Mask" "F.Paste")
			(net 1 "GND")
			(pinfunction "VN_0")
			(pintype "bidirectional")
		)
		(pad "M10" smd circle
			(at -1.5 0.498 90)
			(size 0.5 0.5)
			(layers "F.Cu" "F.Mask" "F.Paste")
			(net 1 "GND")
			(pinfunction "VREFP_0")
			(pintype "bidirectional")
		)
		(pad "M11" smd circle
			(at -0.5 0.498 90)
			(size 0.5 0.5)
			(layers "F.Cu" "F.Mask" "F.Paste")
			(net 1 "GND")
			(pinfunction "GND")
			(pintype "passive")
		)
		(pad "M12" smd circle
			(at 0.498 0.498 90)
			(size 0.5 0.5)
			(layers "F.Cu" "F.Mask" "F.Paste")
			(net 5 "VCC1V8")
			(pinfunction "VCCAUX")
			(pintype "passive")
		)
		(pad "M13" smd circle
			(at 1.499 0.498 90)
			(size 0.5 0.5)
			(layers "F.Cu" "F.Mask" "F.Paste")
			(net 21 "I2C[3]_SDA")
			(pinfunction "IO_L20P_T3_A20_15")
			(pintype "bidirectional")
		)
		(pad "M14" smd circle
			(at 2.499 0.498 90)
			(size 0.5 0.5)
			(layers "F.Cu" "F.Mask" "F.Paste")
			(net 2 "VCC3V3")
			(pinfunction "VCCO_14")
			(pintype "passive")
		)
		(pad "M15" smd circle
			(at 3.499 0.498 90)
			(size 0.5 0.5)
			(layers "F.Cu" "F.Mask" "F.Paste")
			(net 23 "I2C[1]_SDA")
			(pinfunction "IO_L24P_T3_RS1_15")
			(pintype "bidirectional")
		)
		(pad "M16" smd circle
			(at 4.498 0.498 90)
			(size 0.5 0.5)
			(layers "F.Cu" "F.Mask" "F.Paste")
			(net 66 "ESPI_IO1")
			(pinfunction "IO_L24N_T3_RS0_15")
			(pintype "bidirectional")
		)
		(pad "M17" smd circle
			(at 5.499 0.498 90)
			(size 0.5 0.5)
			(layers "F.Cu" "F.Mask" "F.Paste")
			(net 64 "ESPI_RESET_N")
			(pinfunction "IO_25_15")
			(pintype "bidirectional")
		)
		(pad "M18" smd circle
			(at 6.499 0.498 90)
			(size 0.5 0.5)
			(layers "F.Cu" "F.Mask" "F.Paste")
			(net 612 "unconnected-(U14B-IO_L16P_T2_A28_15-PadM18)")
			(pinfunction "IO_L16P_T2_A28_15")
			(pintype "bidirectional+no_connect")
		)
		(pad "M19" smd circle
			(at 7.499 0.498 90)
			(size 0.5 0.5)
			(layers "F.Cu" "F.Mask" "F.Paste")
			(net 1 "GND")
			(pinfunction "GND")
			(pintype "passive")
		)
		(pad "M20" smd circle
			(at 8.499 0.498 90)
			(size 0.5 0.5)
			(layers "F.Cu" "F.Mask" "F.Paste")
			(net 613 "unconnected-(U14B-IO_L18N_T2_A23_15-PadM20)")
			(pinfunction "IO_L18N_T2_A23_15")
			(pintype "bidirectional+no_connect")
		)
		(pad "M21" smd circle
			(at 9.499 0.498 90)
			(size 0.5 0.5)
			(layers "F.Cu" "F.Mask" "F.Paste")
			(net 142 "ETH_MDIO")
			(pinfunction "IO_L10P_T1_AD11P_15")
			(pintype "bidirectional")
		)
		(pad "M22" smd circle
			(at 10.499 0.498 90)
			(size 0.5 0.5)
			(layers "F.Cu" "F.Mask" "F.Paste")
			(net 411 "RGMII_RX_DV")
			(pinfunction "IO_L15N_T2_DQS_ADV_B_15")
			(pintype "bidirectional")
		)
		(pad "N1" smd circle
			(at -10.5 1.499 90)
			(size 0.5 0.5)
			(layers "F.Cu" "F.Mask" "F.Paste")
			(net 3 "VCC1V35")
			(pinfunction "VCCO_35")
			(pintype "passive")
		)
		(pad "N2" smd circle
			(at -9.5 1.499 90)
			(size 0.5 0.5)
			(layers "F.Cu" "F.Mask" "F.Paste")
			(net 148 "DDR3_A7")
			(pinfunction "IO_L22N_T3_35")
			(pintype "bidirectional")
		)
		(pad "N3" smd circle
			(at -8.5 1.499 90)
			(size 0.5 0.5)
			(layers "F.Cu" "F.Mask" "F.Paste")
			(net 146 "DDR3_A6")
			(pinfunction "IO_L19N_T3_VREF_35")
			(pintype "bidirectional")
		)
		(pad "N4" smd circle
			(at -7.5 1.499 90)
			(size 0.5 0.5)
			(layers "F.Cu" "F.Mask" "F.Paste")
			(net 156 "DDR3_A12")
			(pinfunction "IO_L19P_T3_35")
			(pintype "bidirectional")
		)
		(pad "N5" smd circle
			(at -6.5 1.499 90)
			(size 0.5 0.5)
			(layers "F.Cu" "F.Mask" "F.Paste")
			(net 150 "DDR3_A11")
			(pinfunction "IO_L24N_T3_35")
			(pintype "bidirectional")
		)
		(pad "N6" smd circle
			(at -5.5 1.499 90)
			(size 0.5 0.5)
			(layers "F.Cu" "F.Mask" "F.Paste")
			(net 1 "GND")
			(pinfunction "GND")
			(pintype "passive")
		)
		(pad "N7" smd circle
			(at -4.5 1.499 90)
			(size 0.5 0.5)
			(layers "F.Cu" "F.Mask" "F.Paste")
			(net 6 "VCC1V0")
			(pinfunction "VCCINT")
			(pintype "passive")
		)
		(pad "N8" smd circle
			(at -3.5 1.499 90)
			(size 0.5 0.5)
			(layers "F.Cu" "F.Mask" "F.Paste")
			(net 1 "GND")
			(pinfunction "GND")
			(pintype "passive")
		)
		(pad "N9" smd circle
			(at -2.5 1.499 90)
			(size 0.5 0.5)
			(layers "F.Cu" "F.Mask" "F.Paste")
			(net 1 "GND")
			(pinfunction "DXN_0")
			(pintype "bidirectional")
		)
		(pad "N10" smd circle
			(at -1.5 1.499 90)
			(size 0.5 0.5)
			(layers "F.Cu" "F.Mask" "F.Paste")
			(net 1 "GND")
			(pinfunction "DXP_0")
			(pintype "bidirectional")
		)
		(pad "N11" smd circle
			(at -0.5 1.499 90)
			(size 0.5 0.5)
			(layers "F.Cu" "F.Mask" "F.Paste")
			(net 6 "VCC1V0")
			(pinfunction "VCCBRAM")
			(pintype "passive")
		)
		(pad "N12" smd circle
			(at 0.498 1.499 90)
			(size 0.5 0.5)
			(layers "F.Cu" "F.Mask" "F.Paste")
			(net 221 "PROGRAM")
			(pinfunction "PROGRAM_B_0")
			(pintype "bidirectional")
		)
	)
)
